(kicad_pcb
	(version 20260206)
	(generator "pcbnew")
	(generator_version "10.0")
	(general
		(thickness 1.6)
		(legacy_teardrops no)
	)
	(paper "A4")
	(title_block
		(title "01162023_DA0F0TEBIF0_F0T_Expander_BD_F_brd_V02_OCP.brd")
		(comment 1 "Grand Teton / footprints 1310-1314 of 9728")
	)
	(layers
		(0 "F.Cu" signal "TOP")
		(4 "In1.Cu" signal "GND")
		(6 "In2.Cu" signal "VCC")
		(8 "In3.Cu" signal "VCC1")
		(10 "In4.Cu" signal "GND1")
		(12 "In5.Cu" signal "IN1")
		(14 "In6.Cu" signal "GND2")
		(16 "In7.Cu" signal "IN2")
		(18 "In8.Cu" signal "GND3")
		(20 "In9.Cu" signal "IN3")
		(22 "In10.Cu" signal "GND4")
		(24 "In11.Cu" signal "IN4")
		(26 "In12.Cu" signal "GND5")
		(28 "In13.Cu" signal "IN5")
		(30 "In14.Cu" signal "GND6")
		(32 "In15.Cu" signal "IN6")
		(34 "In16.Cu" signal "GND7")
		(2 "B.Cu" signal "BOTTOM")
		(9 "F.Adhes" user "F.Adhesive")
		(11 "B.Adhes" user "B.Adhesive")
		(13 "F.Paste" user "Package Geometry/Pastemask Top")
		(15 "B.Paste" user "Package Geometry/Pastemask Bottom")
		(5 "F.SilkS" user "Ref Des/Silkscreen Top")
		(7 "B.SilkS" user "Ref Des/Silkscreen Bottom")
		(1 "F.Mask" user "Board Geometry/Soldermask Top")
		(3 "B.Mask" user "Board Geometry/Soldermask Bottom")
		(17 "Dwgs.User" user "User.Drawings")
		(19 "Cmts.User" user "User.Comments")
		(21 "Eco1.User" user "User.Eco1")
		(23 "Eco2.User" user "User.Eco2")
		(25 "Edge.Cuts" user "Board Geometry/Outline")
		(27 "Margin" user)
		(31 "F.CrtYd" user "Package Geometry/Place Bound Top")
		(29 "B.CrtYd" user "Package Geometry/Place Bound Bottom")
		(35 "F.Fab" user "Ref Des/Assembly Top")
		(33 "B.Fab" user "Ref Des/Assembly Bottom")
	)
	(footprint ""
		(layer "F.Cu")
		(at 232.988866 -439.16346 180)
		(property "Reference" "X73"
			(at -0.1778 -1.92913 180)
			(unlocked yes)
			(layer "F.SilkS")
			(effects
				(font
					(size 0.7874 0.5842)
					(thickness 0.1524)
				)
				(justify left)
			)
		)
		(property "Value" ""
			(at 0 0 180)
			(layer "F.Fab")
			(effects
				(font
					(size 1.27 1.27)
				)
			)
		)
		(property "Device Type" "TP_TDR_4P_FTS_MPKT4_H025P0200_IO_TP15_TP_TDR_4P_DIP"
			(at 1.30175 1.27 270)
			(unlocked yes)
			(layer "F.Fab")
			(hide yes)
			(effects
				(font
					(size 0.635 0.4064)
					(thickness 0.1524)
				)
			)
		)
		(property "User Part Number" "TP15"
			(at 1.30175 1.27 270)
			(unlocked yes)
			(layer "Cmts.User")
			(hide yes)
			(effects
				(font
					(size 0.635 0.4064)
					(thickness 0.1524)
				)
			)
		)
		(duplicate_pad_numbers_are_jumpers no)
		(fp_line
			(start 2.54 3.81)
			(end 2.54 3.6703)
			(stroke
				(width 0.1524)
				(type default)
			)
			(layer "F.SilkS")
		)
		(fp_line
			(start 2.54 1.4097)
			(end 2.54 1.1303)
			(stroke
				(width 0.1524)
				(type default)
			)
			(layer "F.SilkS")
		)
		(fp_line
			(start 2.54 -1.1303)
			(end 2.54 -1.27)
			(stroke
				(width 0.1524)
				(type default)
			)
			(layer "F.SilkS")
		)
		(fp_line
			(start 2.54 -1.27)
			(end 0 -1.27)
			(stroke
				(width 0.1524)
				(type default)
			)
			(layer "F.SilkS")
		)
		(fp_line
			(start 0 3.81)
			(end 2.54 3.81)
			(stroke
				(width 0.1524)
				(type default)
			)
			(layer "F.SilkS")
		)
		(fp_line
			(start 0 3.175)
			(end 0 3.81)
			(stroke
				(width 0.1524)
				(type default)
			)
			(layer "F.SilkS")
		)
		(fp_line
			(start 0 0.635)
			(end 0 1.905)
			(stroke
				(width 0.1524)
				(type default)
			)
			(layer "F.SilkS")
		)
		(fp_line
			(start 0 -1.27)
			(end 0 -0.635)
			(stroke
				(width 0.1524)
				(type default)
			)
			(layer "F.SilkS")
		)
		(fp_poly
			(pts
				(xy -0.761746 0) (xy -2.285746 -0.762) (xy -2.285746 0.762)
			)
			(stroke
				(width 0)
				(type default)
			)
			(fill yes)
			(layer "F.SilkS")
		)
		(fp_line
			(start 2.54 3.81)
			(end 2.54 -1.27)
			(stroke
				(width 0.1)
				(type default)
			)
			(layer "F.Fab")
		)
		(fp_line
			(start 2.54 -1.27)
			(end 0 -1.27)
			(stroke
				(width 0.1)
				(type default)
			)
			(layer "F.Fab")
		)
		(fp_line
			(start 0 3.81)
			(end 2.54 3.81)
			(stroke
				(width 0.1)
				(type default)
			)
			(layer "F.Fab")
		)
		(fp_line
			(start 0 -1.27)
			(end 0 3.81)
			(stroke
				(width 0.1)
				(type default)
			)
			(layer "F.Fab")
		)
		(fp_poly
			(pts
				(xy -0.761746 0) (xy -2.285746 -0.762) (xy -2.285746 0.762)
			)
			(stroke
				(width 0)
				(type default)
			)
			(fill yes)
			(layer "F.Fab")
		)
		(pad "1" thru_hole circle
			(at 0 0 180)
			(size 1.0033 1.0033)
			(drill 0.249936)
			(layers "*.Cu" "*.Mask")
			(remove_unused_layers no)
			(net "TDR_DIFF_100_IN3_DIN")
			(clearance 0.10795)
			(thermal_gap 0.10795)
			(padstack
				(mode front_inner_back)
				(layer "Inner"
					(shape circle)
					(size 0.8001 0.8001)
					(clearance 0.1524)
				)
				(layer "B.Cu"
					(shape circle)
					(size 1.0033 1.0033)
					(clearance 0.10795)
				)
			)
		)
		(pad "2" thru_hole circle
			(at 2.54 0 180)
			(size 1.9939 1.9939)
			(drill 0.249936)
			(layers "*.Cu" "*.Mask")
			(remove_unused_layers no)
			(net "COUPON_GND1")
			(clearance 0.10795)
			(thermal_gap 0.10795)
			(padstack
				(mode front_inner_back)
				(layer "Inner"
					(shape circle)
					(size 0.8001 0.8001)
					(clearance 0.1524)
				)
				(layer "B.Cu"
					(shape circle)
					(size 1.9939 1.9939)
					(clearance 0.10795)
				)
			)
		)
		(pad "3" thru_hole circle
			(at 2.54 2.54 180)
			(size 1.9939 1.9939)
			(drill 0.249936)
			(layers "*.Cu" "*.Mask")
			(remove_unused_layers no)
			(net "COUPON_GND1")
			(clearance 0.10795)
			(thermal_gap 0.10795)
			(padstack
				(mode front_inner_back)
				(layer "Inner"
					(shape circle)
					(size 0.8001 0.8001)
					(clearance 0.1524)
				)
				(layer "B.Cu"
					(shape circle)
					(size 1.9939 1.9939)
					(clearance 0.10795)
				)
			)
		)
		(pad "4" thru_hole circle
			(at 0 2.54 180)
			(size 1.0033 1.0033)
			(drill 0.249936)
			(layers "*.Cu" "*.Mask")
			(remove_unused_layers no)
			(net "TDR_DIFF_100_IN3_DIP")
			(clearance 0.10795)
			(thermal_gap 0.10795)
			(padstack
				(mode front_inner_back)
				(layer "Inner"
					(shape circle)
					(size 0.8001 0.8001)
					(clearance 0.1524)
				)
				(layer "B.Cu"
					(shape circle)
					(size 1.0033 1.0033)
					(clearance 0.10795)
				)
			)
		)
	)
	(footprint ""
		(layer "F.Cu")
		(at 186.700668 -187.945776 180)
		(property "Reference" "U52"
			(at -1.014984 -2.289556 0)
			(unlocked yes)
			(layer "F.SilkS")
			(effects
				(font
					(size 0.7874 0.5842)
					(thickness 0.1524)
				)
			)
		)
		(property "Value" ""
			(at 0 0 180)
			(layer "F.Fab")
			(effects
				(font
					(size 1.27 1.27)
				)
			)
		)
		(duplicate_pad_numbers_are_jumpers no)
		(fp_line
			(start 2.036064 1.525016)
			(end -2.038096 1.525016)
			(stroke
				(width 0.1524)
				(type default)
			)
			(layer "F.SilkS")
		)
		(fp_line
			(start 2.036064 -1.525016)
			(end 2.036064 1.525016)
			(stroke
				(width 0.1524)
				(type default)
			)
			(layer "F.SilkS")
		)
		(fp_line
			(start 0 -0.6604)
			(end 0.4572 -1.4986)
			(stroke
				(width 0.1524)
				(type default)
			)
			(layer "F.SilkS")
		)
		(fp_line
			(start -0.508 -1.524)
			(end 0 -0.6604)
			(stroke
				(width 0.1524)
				(type default)
			)
			(layer "F.SilkS")
		)
		(fp_line
			(start -2.038096 1.525016)
			(end -2.038096 -1.525016)
			(stroke
				(width 0.1524)
				(type default)
			)
			(layer "F.SilkS")
		)
		(fp_line
			(start -2.038096 -1.525016)
			(end 2.036064 -1.525016)
			(stroke
				(width 0.1524)
				(type default)
			)
			(layer "F.SilkS")
		)
		(fp_poly
			(pts
				(xy -2.71272 -0.592328) (xy -2.71272 -1.217168) (xy -2.159 -0.889)
			)
			(stroke
				(width 0)
				(type default)
			)
			(fill yes)
			(layer "F.SilkS")
		)
		(fp_line
			(start 0.87503 1.525016)
			(end -0.87503 1.525016)
			(stroke
				(width 0.1)
				(type default)
			)
			(layer "F.Fab")
		)
		(fp_line
			(start 0.87503 -1.525016)
			(end 0.87503 1.525016)
			(stroke
				(width 0.1)
				(type default)
			)
			(layer "F.Fab")
		)
		(fp_line
			(start -0.87503 1.525016)
			(end -0.87503 -1.525016)
			(stroke
				(width 0.1)
				(type default)
			)
			(layer "F.Fab")
		)
		(fp_line
			(start -0.87503 -1.525016)
			(end 0.87503 -1.525016)
			(stroke
				(width 0.1)
				(type default)
			)
			(layer "F.Fab")
		)
		(fp_poly
			(pts
				(xy -2.71272 -0.592328) (xy -2.71272 -1.217168) (xy -2.159 -0.889)
			)
			(stroke
				(width 0)
				(type default)
			)
			(fill yes)
			(layer "F.Fab")
		)
		(pad "1" smd rect
			(at -1.35001 -0.94996 90)
			(size 0.6096 1.0668)
			(layers "F.Cu" "F.Mask" "F.Paste")
			(net "SEL_FLASH_PEX0_BUF_R")
		)
		(pad "2" smd rect
			(at -1.35001 0 90)
			(size 0.6096 1.0668)
			(layers "F.Cu" "F.Mask" "F.Paste")
			(net "SEL_FLASH_PEX1_BUF_R")
		)
		(pad "3" smd rect
			(at -1.35001 0.94996 90)
			(size 0.6096 1.0668)
			(layers "F.Cu" "F.Mask" "F.Paste")
			(net "GND")
		)
		(pad "4" smd rect
			(at 1.35001 0.94996 90)
			(size 0.6096 1.0668)
			(layers "F.Cu" "F.Mask" "F.Paste")
			(net "SPI_BIC1_LS01_EN")
		)
		(pad "5" smd rect
			(at 1.35001 -0.94996 90)
			(size 0.6096 1.0668)
			(layers "F.Cu" "F.Mask" "F.Paste")
			(net "P3V3_AUX")
		)
	)
	(footprint ""
		(layer "F.Cu")
		(at 91.63431 -310.478932 -45)
		(property "Reference" "R3943"
			(at 0 0 315)
			(layer "F.SilkS")
			(hide yes)
			(effects
				(font
					(size 1.27 1.27)
				)
			)
		)
		(property "Value" ""
			(at 0 0 315)
			(layer "F.Fab")
			(effects
				(font
					(size 1.27 1.27)
				)
			)
		)
		(duplicate_pad_numbers_are_jumpers no)
		(fp_line
			(start -0.787389 0.406267)
			(end -0.787389 -0.406267)
			(stroke
				(width 0.1524)
				(type default)
			)
			(layer "F.SilkS")
		)
		(fp_line
			(start -0.787389 -0.406267)
			(end 0.787389 -0.406267)
			(stroke
				(width 0.1524)
				(type default)
			)
			(layer "F.SilkS")
		)
		(fp_line
			(start 0.787389 0.406267)
			(end -0.787389 0.406267)
			(stroke
				(width 0.1524)
				(type default)
			)
			(layer "F.SilkS")
		)
		(fp_line
			(start 0.787389 -0.406267)
			(end 0.787389 0.406267)
			(stroke
				(width 0.1524)
				(type default)
			)
			(layer "F.SilkS")
		)
		(fp_line
			(start -0.679446 0.30479)
			(end -0.679446 -0.305149)
			(stroke
				(width 0.1)
				(type default)
			)
			(layer "F.Fab")
		)
		(fp_line
			(start -0.120515 0.30479)
			(end -0.679446 0.30479)
			(stroke
				(width 0.1)
				(type default)
			)
			(layer "F.Fab")
		)
		(fp_line
			(start -0.120695 0.279466)
			(end -0.120515 0.30479)
			(stroke
				(width 0.1)
				(type default)
			)
			(layer "F.Fab")
		)
		(fp_line
			(start -0.679446 -0.305149)
			(end -0.120695 -0.304969)
			(stroke
				(width 0.1)
				(type default)
			)
			(layer "F.Fab")
		)
		(fp_line
			(start 0.120515 0.30479)
			(end 0.120335 0.279466)
			(stroke
				(width 0.1)
				(type default)
			)
			(layer "F.Fab")
		)
		(fp_line
			(start 0.120335 0.279466)
			(end -0.120695 0.279466)
			(stroke
				(width 0.1)
				(type default)
			)
			(layer "F.Fab")
		)
		(fp_line
			(start -0.120695 -0.279466)
			(end 0.120695 -0.279466)
			(stroke
				(width 0.1)
				(type default)
			)
			(layer "F.Fab")
		)
		(fp_line
			(start -0.120695 -0.304969)
			(end -0.120695 -0.279466)
			(stroke
				(width 0.1)
				(type default)
			)
			(layer "F.Fab")
		)
		(fp_line
			(start 0.679446 0.30479)
			(end 0.120515 0.30479)
			(stroke
				(width 0.1)
				(type default)
			)
			(layer "F.Fab")
		)
		(fp_line
			(start 0.120695 -0.279466)
			(end 0.120515 -0.30479)
			(stroke
				(width 0.1)
				(type default)
			)
			(layer "F.Fab")
		)
		(fp_line
			(start 0.120515 -0.30479)
			(end 0.679446 -0.30479)
			(stroke
				(width 0.1)
				(type default)
			)
			(layer "F.Fab")
		)
		(fp_line
			(start 0.679446 -0.30479)
			(end 0.679446 0.30479)
			(stroke
				(width 0.1)
				(type default)
			)
			(layer "F.Fab")
		)
		(pad "1" smd circle
			(at -0.40005 0 315)
			(size 0 0)
			(layers "F.Cu" "F.Mask" "F.Paste")
			(net "PU_PEX0_SIO_BLINK")
		)
		(pad "2" smd circle
			(at 0.40005 0 315)
			(size 0 0)
			(layers "F.Cu" "F.Mask" "F.Paste")
			(net "P1V8_PEX")
		)
	)
	(footprint ""
		(layer "F.Cu")
		(at 57.294018 -35.264852)
		(property "Reference" "R5663"
			(at 0 0 0)
			(layer "F.SilkS")
			(hide yes)
			(effects
				(font
					(size 1.27 1.27)
				)
			)
		)
		(property "Value" ""
			(at 0 0 0)
			(layer "F.Fab")
			(effects
				(font
					(size 1.27 1.27)
				)
			)
		)
		(duplicate_pad_numbers_are_jumpers no)
		(fp_line
			(start -0.7874 -0.4064)
			(end 0.7874 -0.4064)
			(stroke
				(width 0.1524)
				(type default)
			)
			(layer "F.SilkS")
		)
		(fp_line
			(start -0.7874 0.4064)
			(end -0.7874 -0.4064)
			(stroke
				(width 0.1524)
				(type default)
			)
			(layer "F.SilkS")
		)
		(fp_line
			(start 0.7874 -0.4064)
			(end 0.7874 0.4064)
			(stroke
				(width 0.1524)
				(type default)
			)
			(layer "F.SilkS")
		)
		(fp_line
			(start 0.7874 0.4064)
			(end -0.7874 0.4064)
			(stroke
				(width 0.1524)
				(type default)
			)
			(layer "F.SilkS")
		)
		(fp_line
			(start -0.67945 -0.305054)
			(end -0.12065 -0.305054)
			(stroke
				(width 0.1)
				(type default)
			)
			(layer "F.Fab")
		)
		(fp_line
			(start -0.67945 0.3048)
			(end -0.67945 -0.305054)
			(stroke
				(width 0.1)
				(type default)
			)
			(layer "F.Fab")
		)
		(fp_line
			(start -0.12065 -0.305054)
			(end -0.12065 -0.2794)
			(stroke
				(width 0.1)
				(type default)
			)
			(layer "F.Fab")
		)
		(fp_line
			(start -0.12065 -0.2794)
			(end 0.12065 -0.2794)
			(stroke
				(width 0.1)
				(type default)
			)
			(layer "F.Fab")
		)
		(fp_line
			(start -0.12065 0.2794)
			(end -0.12065 0.3048)
			(stroke
				(width 0.1)
				(type default)
			)
			(layer "F.Fab")
		)
		(fp_line
			(start -0.12065 0.3048)
			(end -0.67945 0.3048)
			(stroke
				(width 0.1)
				(type default)
			)
			(layer "F.Fab")
		)
		(fp_line
			(start 0.120396 0.2794)
			(end -0.12065 0.2794)
			(stroke
				(width 0.1)
				(type default)
			)
			(layer "F.Fab")
		)
		(fp_line
			(start 0.120396 0.3048)
			(end 0.120396 0.2794)
			(stroke
				(width 0.1)
				(type default)
			)
			(layer "F.Fab")
		)
		(fp_line
			(start 0.12065 -0.3048)
			(end 0.67945 -0.3048)
			(stroke
				(width 0.1)
				(type default)
			)
			(layer "F.Fab")
		)
		(fp_line
			(start 0.12065 -0.2794)
			(end 0.12065 -0.3048)
			(stroke
				(width 0.1)
				(type default)
			)
			(layer "F.Fab")
		)
		(fp_line
			(start 0.67945 -0.3048)
			(end 0.67945 0.3048)
			(stroke
				(width 0.1)
				(type default)
			)
			(layer "F.Fab")
		)
		(fp_line
			(start 0.67945 0.3048)
			(end 0.120396 0.3048)
			(stroke
				(width 0.1)
				(type default)
			)
			(layer "F.Fab")
		)
		(pad "1" smd circle
			(at -0.40005 0)
			(size 0 0)
			(layers "F.Cu" "F.Mask" "F.Paste")
			(net "RST_SMB_SSD2_ISO_N")
		)
		(pad "2" smd circle
			(at 0.40005 0)
			(size 0 0)
			(layers "F.Cu" "F.Mask" "F.Paste")
			(net "GND")
		)
	)
	(footprint ""
		(layer "F.Cu")
		(at 149.387814 -298.020232)
		(property "Reference" "C3195"
			(at 0 0 0)
			(layer "F.SilkS")
			(hide yes)
			(effects
				(font
					(size 1.27 1.27)
				)
			)
		)
		(property "Value" ""
			(at 0 0 0)
			(layer "F.Fab")
			(effects
				(font
					(size 1.27 1.27)
				)
			)
		)
		(duplicate_pad_numbers_are_jumpers no)
		(fp_line
			(start -1.2954 -0.5842)
			(end 1.2954 -0.5842)
			(stroke
				(width 0.1524)
				(type default)
			)
			(layer "F.SilkS")
		)
		(fp_line
			(start -1.2954 0.5842)
			(end -1.2954 -0.5842)
			(stroke
				(width 0.1524)
				(type default)
			)
			(layer "F.SilkS")
		)
		(fp_line
			(start 1.2954 -0.5842)
			(end 1.2954 0.5842)
			(stroke
				(width 0.1524)
				(type default)
			)
			(layer "F.SilkS")
		)
		(fp_line
			(start 1.2954 0.5842)
			(end -1.2954 0.5842)
			(stroke
				(width 0.1524)
				(type default)
			)
			(layer "F.SilkS")
		)
		(fp_line
			(start -1.1938 -0.4064)
			(end -0.8636 -0.4064)
			(stroke
				(width 0.1)
				(type default)
			)
			(layer "F.Fab")
		)
		(fp_line
			(start -1.1938 0.4064)
			(end -1.1938 -0.4064)
			(stroke
				(width 0.1)
				(type default)
			)
			(layer "F.Fab")
		)
		(fp_line
			(start -0.8636 -0.4572)
			(end 0.8636 -0.4572)
			(stroke
				(width 0.1)
				(type default)
			)
			(layer "F.Fab")
		)
		(fp_line
			(start -0.8636 -0.4064)
			(end -0.8636 -0.4572)
			(stroke
				(width 0.1)
				(type default)
			)
			(layer "F.Fab")
		)
		(fp_line
			(start -0.8636 0.4064)
			(end -1.1938 0.4064)
			(stroke
				(width 0.1)
				(type default)
			)
			(layer "F.Fab")
		)
		(fp_line
			(start -0.8636 0.4572)
			(end -0.8636 0.4064)
			(stroke
				(width 0.1)
				(type default)
			)
			(layer "F.Fab")
		)
		(fp_line
			(start 0.8636 -0.4572)
			(end 0.8636 -0.4064)
			(stroke
				(width 0.1)
				(type default)
			)
			(layer "F.Fab")
		)
		(fp_line
			(start 0.8636 -0.4064)
			(end 1.1938 -0.4064)
			(stroke
				(width 0.1)
				(type default)
			)
			(layer "F.Fab")
		)
		(fp_line
			(start 0.8636 0.4064)
			(end 0.8636 0.4572)
			(stroke
				(width 0.1)
				(type default)
			)
			(layer "F.Fab")
		)
		(fp_line
			(start 0.8636 0.4572)
			(end -0.8636 0.4572)
			(stroke
				(width 0.1)
				(type default)
			)
			(layer "F.Fab")
		)
		(fp_line
			(start 1.1938 -0.4064)
			(end 1.1938 0.4064)
			(stroke
				(width 0.1)
				(type default)
			)
			(layer "F.Fab")
		)
		(fp_line
			(start 1.1938 0.4064)
			(end 0.8636 0.4064)
			(stroke
				(width 0.1)
				(type default)
			)
			(layer "F.Fab")
		)
		(pad "1" smd rect
			(at -0.7366 0 270)
			(size 0.7112 0.8128)
			(layers "F.Cu" "F.Mask" "F.Paste")
			(net "PCEPLL0_VDDA18_PEX1")
		)
		(pad "2" smd rect
			(at 0.7366 0 270)
			(size 0.7112 0.8128)
			(layers "F.Cu" "F.Mask" "F.Paste")
			(net "GND")
		)
	)
)
